# T6G (Grand Teton) — schematic netlist excerpt (pin names and nets, part order shuffled) for the footprints in the layout excerpt that follows; sources: Cadence DE-HDL packaged netlist, KiCad conversion of 04192023_DAF0TMB3IC0_F0TG_MB_C_brd_V02_OCP.brd

C6066  Q_CAP  22UF 6.3V 20% X6S  pkg C0603  page 177 : A = P1V2_AUX ; B = GND
C330  Q_CAP  1UF 4V 20% X6S  pkg 0201  page 334 : A = P0V9_CPU1_RT1_2A ; B = GND
C6071  Q_CAP  0.001UF 50V 10% X7R  pkg C0402  page 177 : A = P1V2_AUX ; B = GND

(kicad_pcb
	(version 20260206)
	(generator "pcbnew")
	(generator_version "10.0")
	(general
		(thickness 1.6)
		(legacy_teardrops no)
	)
	(paper "A4")
	(title_block
		(title "04192023_DAF0TMB3IC0_F0TG_MB_C_brd_V02_OCP.brd")
		(comment 1 "Grand Teton / footprints 7393-7395 of 8354")
	)
	(layers
		(0 "F.Cu" signal "TOP")
		(4 "In1.Cu" signal "GND")
		(6 "In2.Cu" signal "IN1")
		(8 "In3.Cu" signal "GND1")
		(10 "In4.Cu" signal "IN2")
		(12 "In5.Cu" signal "GND2")
		(14 "In6.Cu" signal "IN3")
		(16 "In7.Cu" signal "GND3")
		(18 "In8.Cu" signal "VCC")
		(20 "In9.Cu" signal "VCC1")
		(22 "In10.Cu" signal "GND4")
		(24 "In11.Cu" signal "IN4")
		(26 "In12.Cu" signal "GND5")
		(28 "In13.Cu" signal "IN5")
		(30 "In14.Cu" signal "GND6")
		(32 "In15.Cu" signal "IN6")
		(34 "In16.Cu" signal "GND7")
		(2 "B.Cu" signal "BOTTOM")
		(9 "F.Adhes" user "F.Adhesive")
		(11 "B.Adhes" user "B.Adhesive")
		(13 "F.Paste" user "Package Geometry/Pastemask Top")
		(15 "B.Paste" user "Package Geometry/Pastemask Bottom")
		(5 "F.SilkS" user "Ref Des/Silkscreen Top")
		(7 "B.SilkS" user "Ref Des/Silkscreen Bottom")
		(1 "F.Mask" user "Board Geometry/Soldermask Top")
		(3 "B.Mask" user "Board Geometry/Soldermask Bottom")
		(17 "Dwgs.User" user "User.Drawings")
		(19 "Cmts.User" user "User.Comments")
		(21 "Eco1.User" user "User.Eco1")
		(23 "Eco2.User" user "User.Eco2")
		(25 "Edge.Cuts" user "Board Geometry/Outline")
		(27 "Margin" user)
		(31 "F.CrtYd" user "Package Geometry/Place Bound Top")
		(29 "B.CrtYd" user "Package Geometry/Place Bound Bottom")
		(35 "F.Fab" user "Ref Des/Assembly Top")
		(33 "B.Fab" user "Ref Des/Assembly Bottom")
	)
	(footprint ""
		(layer "B.Cu")
		(at 127.319024 -31.259272)
		(property "Reference" "C6066"
			(at 0 0 0)
			(layer "B.SilkS")
			(hide yes)
			(effects
				(font
					(size 1.27 1.27)
				)
				(justify mirror)
			)
		)
		(property "Value" ""
			(at 0 0 0)
			(layer "B.Fab")
			(effects
				(font
					(size 1.27 1.27)
				)
				(justify mirror)
			)
		)
		(duplicate_pad_numbers_are_jumpers no)
		(fp_line
			(start -1.2954 -0.5842)
			(end -1.2954 0.5842)
			(stroke
				(width 0.1524)
				(type default)
			)
			(layer "B.SilkS")
		)
		(fp_line
			(start -1.2954 0.5842)
			(end 1.2954 0.5842)
			(stroke
				(width 0.1524)
				(type default)
			)
			(layer "B.SilkS")
		)
		(fp_line
			(start 1.2954 -0.5842)
			(end -1.2954 -0.5842)
			(stroke
				(width 0.1524)
				(type default)
			)
			(layer "B.SilkS")
		)
		(fp_line
			(start 1.2954 0.5842)
			(end 1.2954 -0.5842)
			(stroke
				(width 0.1524)
				(type default)
			)
			(layer "B.SilkS")
		)
		(fp_line
			(start -1.1938 -0.4064)
			(end -1.1938 0.4064)
			(stroke
				(width 0.1)
				(type default)
			)
			(layer "B.Fab")
		)
		(fp_line
			(start -1.1938 0.4064)
			(end -0.8636 0.4064)
			(stroke
				(width 0.1)
				(type default)
			)
			(layer "B.Fab")
		)
		(fp_line
			(start -0.8636 -0.4572)
			(end -0.8636 -0.4064)
			(stroke
				(width 0.1)
				(type default)
			)
			(layer "B.Fab")
		)
		(fp_line
			(start -0.8636 -0.4064)
			(end -1.1938 -0.4064)
			(stroke
				(width 0.1)
				(type default)
			)
			(layer "B.Fab")
		)
		(fp_line
			(start -0.8636 0.4064)
			(end -0.8636 0.4572)
			(stroke
				(width 0.1)
				(type default)
			)
			(layer "B.Fab")
		)
		(fp_line
			(start -0.8636 0.4572)
			(end 0.8636 0.4572)
			(stroke
				(width 0.1)
				(type default)
			)
			(layer "B.Fab")
		)
		(fp_line
			(start 0.8636 -0.4572)
			(end -0.8636 -0.4572)
			(stroke
				(width 0.1)
				(type default)
			)
			(layer "B.Fab")
		)
		(fp_line
			(start 0.8636 -0.4064)
			(end 0.8636 -0.4572)
			(stroke
				(width 0.1)
				(type default)
			)
			(layer "B.Fab")
		)
		(fp_line
			(start 0.8636 0.4064)
			(end 1.1938 0.4064)
			(stroke
				(width 0.1)
				(type default)
			)
			(layer "B.Fab")
		)
		(fp_line
			(start 0.8636 0.4572)
			(end 0.8636 0.4064)
			(stroke
				(width 0.1)
				(type default)
			)
			(layer "B.Fab")
		)
		(fp_line
			(start 1.1938 -0.4064)
			(end 0.8636 -0.4064)
			(stroke
				(width 0.1)
				(type default)
			)
			(layer "B.Fab")
		)
		(fp_line
			(start 1.1938 0.4064)
			(end 1.1938 -0.4064)
			(stroke
				(width 0.1)
				(type default)
			)
			(layer "B.Fab")
		)
		(pad "1" smd rect
			(at 0.7366 0 270)
			(size 0.7112 0.8128)
			(layers "B.Cu" "B.Mask" "B.Paste")
			(net "P1V2_AUX")
		)
		(pad "2" smd rect
			(at -0.7366 0 270)
			(size 0.7112 0.8128)
			(layers "B.Cu" "B.Mask" "B.Paste")
			(net "GND")
		)
	)
	(footprint ""
		(layer "B.Cu")
		(at 128.811528 -40.106092 180)
		(property "Reference" "C6071"
			(at 0 0 0)
			(layer "B.SilkS")
			(hide yes)
			(effects
				(font
					(size 1.27 1.27)
				)
				(justify mirror)
			)
		)
		(property "Value" ""
			(at 0 0 0)
			(layer "B.Fab")
			(effects
				(font
					(size 1.27 1.27)
				)
				(justify mirror)
			)
		)
		(duplicate_pad_numbers_are_jumpers no)
		(fp_line
			(start 0.7874 0.4064)
			(end 0.7874 -0.4064)
			(stroke
				(width 0.1524)
				(type default)
			)
			(layer "B.SilkS")
		)
		(fp_line
			(start 0.7874 -0.4064)
			(end -0.7874 -0.4064)
			(stroke
				(width 0.1524)
				(type default)
			)
			(layer "B.SilkS")
		)
		(fp_line
			(start -0.7874 0.4064)
			(end 0.7874 0.4064)
			(stroke
				(width 0.1524)
				(type default)
			)
			(layer "B.SilkS")
		)
		(fp_line
			(start -0.7874 -0.4064)
			(end -0.7874 0.4064)
			(stroke
				(width 0.1524)
				(type default)
			)
			(layer "B.SilkS")
		)
		(fp_line
			(start 0.67945 0.3048)
			(end 0.67945 -0.305054)
			(stroke
				(width 0.1)
				(type default)
			)
			(layer "B.Fab")
		)
		(fp_line
			(start 0.67945 -0.305054)
			(end 0.12065 -0.305054)
			(stroke
				(width 0.1)
				(type default)
			)
			(layer "B.Fab")
		)
		(fp_line
			(start 0.12065 0.3048)
			(end 0.67945 0.3048)
			(stroke
				(width 0.1)
				(type default)
			)
			(layer "B.Fab")
		)
		(fp_line
			(start 0.12065 0.2794)
			(end 0.12065 0.3048)
			(stroke
				(width 0.1)
				(type default)
			)
			(layer "B.Fab")
		)
		(fp_line
			(start 0.12065 -0.2794)
			(end -0.12065 -0.2794)
			(stroke
				(width 0.1)
				(type default)
			)
			(layer "B.Fab")
		)
		(fp_line
			(start 0.12065 -0.305054)
			(end 0.12065 -0.2794)
			(stroke
				(width 0.1)
				(type default)
			)
			(layer "B.Fab")
		)
		(fp_line
			(start -0.120396 0.3048)
			(end -0.120396 0.2794)
			(stroke
				(width 0.1)
				(type default)
			)
			(layer "B.Fab")
		)
		(fp_line
			(start -0.120396 0.2794)
			(end 0.12065 0.2794)
			(stroke
				(width 0.1)
				(type default)
			)
			(layer "B.Fab")
		)
		(fp_line
			(start -0.12065 -0.2794)
			(end -0.12065 -0.3048)
			(stroke
				(width 0.1)
				(type default)
			)
			(layer "B.Fab")
		)
		(fp_line
			(start -0.12065 -0.3048)
			(end -0.67945 -0.3048)
			(stroke
				(width 0.1)
				(type default)
			)
			(layer "B.Fab")
		)
		(fp_line
			(start -0.67945 0.3048)
			(end -0.120396 0.3048)
			(stroke
				(width 0.1)
				(type default)
			)
			(layer "B.Fab")
		)
		(fp_line
			(start -0.67945 -0.3048)
			(end -0.67945 0.3048)
			(stroke
				(width 0.1)
				(type default)
			)
			(layer "B.Fab")
		)
		(pad "1" smd circle
			(at 0.40005 0)
			(size 0 0)
			(layers "B.Cu" "B.Mask" "B.Paste")
			(net "P1V2_AUX")
		)
		(pad "2" smd circle
			(at -0.40005 0)
			(size 0 0)
			(layers "B.Cu" "B.Mask" "B.Paste")
			(net "GND")
		)
	)
	(footprint ""
		(layer "B.Cu")
		(at 81.106264 -386.766562 90)
		(property "Reference" "C330"
			(at 0 0 90)
			(layer "B.SilkS")
			(hide yes)
			(effects
				(font
					(size 1.27 1.27)
				)
				(justify mirror)
			)
		)
		(property "Value" ""
			(at 0 0 90)
			(layer "B.Fab")
			(effects
				(font
					(size 1.27 1.27)
				)
				(justify mirror)
			)
		)
		(duplicate_pad_numbers_are_jumpers no)
		(fp_line
			(start 0.299974 -0.150114)
			(end -0.299974 -0.150114)
			(stroke
				(width 0.1)
				(type default)
			)
			(layer "B.Fab")
		)
		(fp_line
			(start -0.299974 -0.150114)
			(end -0.299974 0.150114)
			(stroke
				(width 0.1)
				(type default)
			)
			(layer "B.Fab")
		)
		(fp_line
			(start 0.299974 0.150114)
			(end 0.299974 -0.150114)
			(stroke
				(width 0.1)
				(type default)
			)
			(layer "B.Fab")
		)
		(fp_line
			(start -0.299974 0.150114)
			(end 0.299974 0.150114)
			(stroke
				(width 0.1)
				(type default)
			)
			(layer "B.Fab")
		)
		(pad "1" smd rect
			(at 0.2667 0 270)
			(size 0.3048 0.381)
			(layers "B.Cu" "B.Mask" "B.Paste")
			(net "P0V9_CPU1_RT1_2A")
		)
		(pad "2" smd rect
			(at -0.2667 0 270)
			(size 0.3048 0.381)
			(layers "B.Cu" "B.Mask" "B.Paste")
			(net "GND")
		)
	)
)
